# T6G (Grand Teton) — schematic netlist excerpt (pin names and nets, part order shuffled) for the footprints in the layout excerpt that follows; sources: Cadence DE-HDL packaged netlist, KiCad conversion of 04192023_DAF0TMB3IC0_F0TG_MB_C_brd_V02_OCP.brd

PR6616  Q_RES  0 5% CHIP  pkg 0402LF  page 362 : A = P0V9_RETIMER_CPU0_VRHOT ; B = TP_P0V9_RETIMER_CPU0_VRHOT
C6550  Q_CAP_DIFFBUS  DIFF BUS_0.22UF 6.3V 20% X6S  pkg C0201  page 286 : \1\ = P5E_CPU0_P1_TX_BUF_C_DN<8> ; \2\ = P5E_CPU0_P1_TX_BUF_DN<8>
R1588  Q_RES  49.9 1% CHIP  pkg 0402LF  page 106 : A = I3C_SPD_DDRGL_CPU1_SCL ; B = I3C_SPD_DDRI_CPU1_SCL

(kicad_pcb
	(version 20260206)
	(generator "pcbnew")
	(generator_version "10.0")
	(general
		(thickness 1.6)
		(legacy_teardrops no)
	)
	(paper "A4")
	(title_block
		(title "04192023_DAF0TMB3IC0_F0TG_MB_C_brd_V02_OCP.brd")
		(comment 1 "Grand Teton / footprints 5893-5895 of 8354")
	)
	(layers
		(0 "F.Cu" signal "TOP")
		(4 "In1.Cu" signal "GND")
		(6 "In2.Cu" signal "IN1")
		(8 "In3.Cu" signal "GND1")
		(10 "In4.Cu" signal "IN2")
		(12 "In5.Cu" signal "GND2")
		(14 "In6.Cu" signal "IN3")
		(16 "In7.Cu" signal "GND3")
		(18 "In8.Cu" signal "VCC")
		(20 "In9.Cu" signal "VCC1")
		(22 "In10.Cu" signal "GND4")
		(24 "In11.Cu" signal "IN4")
		(26 "In12.Cu" signal "GND5")
		(28 "In13.Cu" signal "IN5")
		(30 "In14.Cu" signal "GND6")
		(32 "In15.Cu" signal "IN6")
		(34 "In16.Cu" signal "GND7")
		(2 "B.Cu" signal "BOTTOM")
		(9 "F.Adhes" user "F.Adhesive")
		(11 "B.Adhes" user "B.Adhesive")
		(13 "F.Paste" user "Package Geometry/Pastemask Top")
		(15 "B.Paste" user "Package Geometry/Pastemask Bottom")
		(5 "F.SilkS" user "Ref Des/Silkscreen Top")
		(7 "B.SilkS" user "Ref Des/Silkscreen Bottom")
		(1 "F.Mask" user "Board Geometry/Soldermask Top")
		(3 "B.Mask" user "Board Geometry/Soldermask Bottom")
		(17 "Dwgs.User" user "User.Drawings")
		(19 "Cmts.User" user "User.Comments")
		(21 "Eco1.User" user "User.Eco1")
		(23 "Eco2.User" user "User.Eco2")
		(25 "Edge.Cuts" user "Board Geometry/Outline")
		(27 "Margin" user)
		(31 "F.CrtYd" user "Package Geometry/Place Bound Top")
		(29 "B.CrtYd" user "Package Geometry/Place Bound Bottom")
		(35 "F.Fab" user "Ref Des/Assembly Top")
		(33 "B.Fab" user "Ref Des/Assembly Bottom")
	)
	(footprint ""
		(layer "B.Cu")
		(at 439.782966 -425.184824 -90)
		(property "Reference" "PR6616"
			(at 0 0 90)
			(layer "B.SilkS")
			(hide yes)
			(effects
				(font
					(size 1.27 1.27)
				)
				(justify mirror)
			)
		)
		(property "Value" ""
			(at 0 0 90)
			(layer "B.Fab")
			(effects
				(font
					(size 1.27 1.27)
				)
				(justify mirror)
			)
		)
		(duplicate_pad_numbers_are_jumpers no)
		(fp_line
			(start -0.7874 0.4064)
			(end 0.7874 0.4064)
			(stroke
				(width 0.1524)
				(type default)
			)
			(layer "B.SilkS")
		)
		(fp_line
			(start 0.7874 0.4064)
			(end 0.7874 -0.4064)
			(stroke
				(width 0.1524)
				(type default)
			)
			(layer "B.SilkS")
		)
		(fp_line
			(start -0.7874 -0.4064)
			(end -0.7874 0.4064)
			(stroke
				(width 0.1524)
				(type default)
			)
			(layer "B.SilkS")
		)
		(fp_line
			(start 0.7874 -0.4064)
			(end -0.7874 -0.4064)
			(stroke
				(width 0.1524)
				(type default)
			)
			(layer "B.SilkS")
		)
		(fp_line
			(start -0.67945 0.3048)
			(end -0.120396 0.3048)
			(stroke
				(width 0.1)
				(type default)
			)
			(layer "B.Fab")
		)
		(fp_line
			(start -0.120396 0.3048)
			(end -0.120396 0.2794)
			(stroke
				(width 0.1)
				(type default)
			)
			(layer "B.Fab")
		)
		(fp_line
			(start 0.12065 0.3048)
			(end 0.67945 0.3048)
			(stroke
				(width 0.1)
				(type default)
			)
			(layer "B.Fab")
		)
		(fp_line
			(start 0.67945 0.3048)
			(end 0.67945 -0.305054)
			(stroke
				(width 0.1)
				(type default)
			)
			(layer "B.Fab")
		)
		(fp_line
			(start -0.120396 0.2794)
			(end 0.12065 0.2794)
			(stroke
				(width 0.1)
				(type default)
			)
			(layer "B.Fab")
		)
		(fp_line
			(start 0.12065 0.2794)
			(end 0.12065 0.3048)
			(stroke
				(width 0.1)
				(type default)
			)
			(layer "B.Fab")
		)
		(fp_line
			(start -0.12065 -0.2794)
			(end -0.12065 -0.3048)
			(stroke
				(width 0.1)
				(type default)
			)
			(layer "B.Fab")
		)
		(fp_line
			(start 0.12065 -0.2794)
			(end -0.12065 -0.2794)
			(stroke
				(width 0.1)
				(type default)
			)
			(layer "B.Fab")
		)
		(fp_line
			(start -0.67945 -0.3048)
			(end -0.67945 0.3048)
			(stroke
				(width 0.1)
				(type default)
			)
			(layer "B.Fab")
		)
		(fp_line
			(start -0.12065 -0.3048)
			(end -0.67945 -0.3048)
			(stroke
				(width 0.1)
				(type default)
			)
			(layer "B.Fab")
		)
		(fp_line
			(start 0.12065 -0.305054)
			(end 0.12065 -0.2794)
			(stroke
				(width 0.1)
				(type default)
			)
			(layer "B.Fab")
		)
		(fp_line
			(start 0.67945 -0.305054)
			(end 0.12065 -0.305054)
			(stroke
				(width 0.1)
				(type default)
			)
			(layer "B.Fab")
		)
		(pad "1" smd circle
			(at 0.40005 0 90)
			(size 0 0)
			(layers "B.Cu" "B.Mask" "B.Paste")
			(net "P0V9_RETIMER_CPU0_VRHOT")
		)
		(pad "2" smd circle
			(at -0.40005 0 90)
			(size 0 0)
			(layers "B.Cu" "B.Mask" "B.Paste")
			(net "TP_P0V9_RETIMER_CPU0_VRHOT")
		)
	)
	(footprint ""
		(layer "B.Cu")
		(at 329.806046 -416.899344 90)
		(property "Reference" "C6550"
			(at 0 0 90)
			(layer "B.SilkS")
			(hide yes)
			(effects
				(font
					(size 1.27 1.27)
				)
				(justify mirror)
			)
		)
		(property "Value" ""
			(at 0 0 90)
			(layer "B.Fab")
			(effects
				(font
					(size 1.27 1.27)
				)
				(justify mirror)
			)
		)
		(duplicate_pad_numbers_are_jumpers no)
		(fp_line
			(start 0.299974 -0.150114)
			(end -0.299974 -0.150114)
			(stroke
				(width 0.1)
				(type default)
			)
			(layer "B.Fab")
		)
		(fp_line
			(start -0.299974 -0.150114)
			(end -0.299974 0.150114)
			(stroke
				(width 0.1)
				(type default)
			)
			(layer "B.Fab")
		)
		(fp_line
			(start 0.299974 0.150114)
			(end 0.299974 -0.150114)
			(stroke
				(width 0.1)
				(type default)
			)
			(layer "B.Fab")
		)
		(fp_line
			(start -0.299974 0.150114)
			(end 0.299974 0.150114)
			(stroke
				(width 0.1)
				(type default)
			)
			(layer "B.Fab")
		)
		(pad "1" smd rect
			(at 0.2667 0 270)
			(size 0.3048 0.381)
			(layers "B.Cu" "B.Mask" "B.Paste")
			(net "P5E_CPU0_P1_TX_BUF_C_DN<8>")
		)
		(pad "2" smd rect
			(at -0.2667 0 270)
			(size 0.3048 0.381)
			(layers "B.Cu" "B.Mask" "B.Paste")
			(net "P5E_CPU0_P1_TX_BUF_DN<8>")
		)
	)
	(footprint ""
		(layer "B.Cu")
		(at 182.860696 -194.8942 180)
		(property "Reference" "R1588"
			(at 0 0 0)
			(layer "B.SilkS")
			(hide yes)
			(effects
				(font
					(size 1.27 1.27)
				)
				(justify mirror)
			)
		)
		(property "Value" ""
			(at 0 0 0)
			(layer "B.Fab")
			(effects
				(font
					(size 1.27 1.27)
				)
				(justify mirror)
			)
		)
		(duplicate_pad_numbers_are_jumpers no)
		(fp_line
			(start 0.7874 0.4064)
			(end 0.7874 -0.4064)
			(stroke
				(width 0.1524)
				(type default)
			)
			(layer "B.SilkS")
		)
		(fp_line
			(start 0.7874 -0.4064)
			(end -0.7874 -0.4064)
			(stroke
				(width 0.1524)
				(type default)
			)
			(layer "B.SilkS")
		)
		(fp_line
			(start -0.7874 0.4064)
			(end 0.7874 0.4064)
			(stroke
				(width 0.1524)
				(type default)
			)
			(layer "B.SilkS")
		)
		(fp_line
			(start -0.7874 -0.4064)
			(end -0.7874 0.4064)
			(stroke
				(width 0.1524)
				(type default)
			)
			(layer "B.SilkS")
		)
		(fp_line
			(start 0.67945 0.3048)
			(end 0.67945 -0.305054)
			(stroke
				(width 0.1)
				(type default)
			)
			(layer "B.Fab")
		)
		(fp_line
			(start 0.67945 -0.305054)
			(end 0.12065 -0.305054)
			(stroke
				(width 0.1)
				(type default)
			)
			(layer "B.Fab")
		)
		(fp_line
			(start 0.12065 0.3048)
			(end 0.67945 0.3048)
			(stroke
				(width 0.1)
				(type default)
			)
			(layer "B.Fab")
		)
		(fp_line
			(start 0.12065 0.2794)
			(end 0.12065 0.3048)
			(stroke
				(width 0.1)
				(type default)
			)
			(layer "B.Fab")
		)
		(fp_line
			(start 0.12065 -0.2794)
			(end -0.12065 -0.2794)
			(stroke
				(width 0.1)
				(type default)
			)
			(layer "B.Fab")
		)
		(fp_line
			(start 0.12065 -0.305054)
			(end 0.12065 -0.2794)
			(stroke
				(width 0.1)
				(type default)
			)
			(layer "B.Fab")
		)
		(fp_line
			(start -0.120396 0.3048)
			(end -0.120396 0.2794)
			(stroke
				(width 0.1)
				(type default)
			)
			(layer "B.Fab")
		)
		(fp_line
			(start -0.120396 0.2794)
			(end 0.12065 0.2794)
			(stroke
				(width 0.1)
				(type default)
			)
			(layer "B.Fab")
		)
		(fp_line
			(start -0.12065 -0.2794)
			(end -0.12065 -0.3048)
			(stroke
				(width 0.1)
				(type default)
			)
			(layer "B.Fab")
		)
		(fp_line
			(start -0.12065 -0.3048)
			(end -0.67945 -0.3048)
			(stroke
				(width 0.1)
				(type default)
			)
			(layer "B.Fab")
		)
		(fp_line
			(start -0.67945 0.3048)
			(end -0.120396 0.3048)
			(stroke
				(width 0.1)
				(type default)
			)
			(layer "B.Fab")
		)
		(fp_line
			(start -0.67945 -0.3048)
			(end -0.67945 0.3048)
			(stroke
				(width 0.1)
				(type default)
			)
			(layer "B.Fab")
		)
		(pad "1" smd circle
			(at 0.40005 0)
			(size 0 0)
			(layers "B.Cu" "B.Mask" "B.Paste")
			(net "I3C_SPD_DDRGL_CPU1_SCL")
		)
		(pad "2" smd circle
			(at -0.40005 0)
			(size 0 0)
			(layers "B.Cu" "B.Mask" "B.Paste")
			(net "I3C_SPD_DDRI_CPU1_SCL")
		)
	)
)
